FILE_TYPE = CONNECTIVITY;
{Allegro Design Entry HDL 17.2-2016 S081 (4005846) 1/11/2022}
"PAGE_NUMBER" = 160;
0"NC";
END.
